# BASEBOARD_FAB2 (Tioga Pass) — schematic netlist excerpt (pin names and nets, part order shuffled) for the footprints in the layout excerpt that follows; sources: Cadence DE-HDL packaged netlist, KiCad conversion of Wiwynn_Tioga_Pass_MB.brd

C3P18  CAP  0.22UF 16V 10% X7R  pkg 0402  page 107 : A = P3E_CPU0_PE1_SS_TXP<2> ; B = P3E_CPU0_PE1_PCH_TXP<2>
R25W167  RES  1.00K 1% CHIP  pkg 0402  page 254 : A = BMC_TCK_MUX_SEL ; B = GND
R25W24  120R2F-GP  1%  pkg RCL_GP  page 151 : \1\ = GND ; \2\ = BMC_M_A12

(kicad_pcb
	(version 20260206)
	(generator "pcbnew")
	(generator_version "10.0")
	(general
		(thickness 1.6)
		(legacy_teardrops no)
	)
	(paper "A4")
	(title_block
		(title "Wiwynn_Tioga_Pass_MB.brd")
		(comment 1 "Tioga Pass / footprints 2792-2794 of 4770")
	)
	(layers
		(0 "F.Cu" signal "TOP")
		(4 "In1.Cu" signal "L2GND")
		(6 "In2.Cu" signal "L3")
		(8 "In3.Cu" signal "L4GND")
		(10 "In4.Cu" signal "L5")
		(12 "In5.Cu" signal "L6GND")
		(14 "In6.Cu" signal "L7VCC")
		(16 "In7.Cu" signal "L8VCC")
		(18 "In8.Cu" signal "L9GND")
		(20 "In9.Cu" signal "L10")
		(22 "In10.Cu" signal "L11GND")
		(24 "In11.Cu" signal "L12")
		(26 "In12.Cu" signal "L13GND")
		(2 "B.Cu" signal "BOTTOM")
		(9 "F.Adhes" user "F.Adhesive")
		(11 "B.Adhes" user "B.Adhesive")
		(13 "F.Paste" user "Package Geometry/Pastemask Top")
		(15 "B.Paste" user "Package Geometry/Pastemask Bottom")
		(5 "F.SilkS" user "Ref Des/Silkscreen Top")
		(7 "B.SilkS" user "Ref Des/Silkscreen Bottom")
		(1 "F.Mask" user "Board Geometry/Soldermask Top")
		(3 "B.Mask" user "Board Geometry/Soldermask Bottom")
		(17 "Dwgs.User" user "User.Drawings")
		(19 "Cmts.User" user "User.Comments")
		(21 "Eco1.User" user "User.Eco1")
		(23 "Eco2.User" user "User.Eco2")
		(25 "Edge.Cuts" user "Board Geometry/Outline")
		(27 "Margin" user)
		(31 "F.CrtYd" user "Package Geometry/Place Bound Top")
		(29 "B.CrtYd" user "Package Geometry/Place Bound Bottom")
		(35 "F.Fab" user "Ref Des/Assembly Top")
		(33 "B.Fab" user "Ref Des/Assembly Bottom")
	)
	(footprint ""
		(layer "B.Cu")
		(at 439.6613 -147.955 180)
		(property "Reference" "R25W167"
			(at 0.8382 -0.67818 180)
			(unlocked yes)
			(layer "B.SilkS")
			(effects
				(font
					(size 0.4064 0.254)
					(thickness 0.1524)
				)
				(justify left mirror)
			)
		)
		(property "Value" ""
			(at 0 0 0)
			(layer "B.Fab")
			(effects
				(font
					(size 1.27 1.27)
				)
				(justify mirror)
			)
		)
		(duplicate_pad_numbers_are_jumpers no)
		(fp_poly
			(pts
				(xy 0.2794 -0.1016) (xy -0.2794 -0.1016) (xy -0.2794 0.9906) (xy 0.2794 0.9906)
			)
			(stroke
				(width 0)
				(type default)
			)
			(fill no)
			(layer "B.CrtYd")
		)
		(fp_line
			(start 0.2794 0.9906)
			(end -0.2794 0.9906)
			(stroke
				(width 0.1)
				(type default)
			)
			(layer "B.Fab")
		)
		(fp_line
			(start 0.2794 -0.1016)
			(end 0.2794 0.9906)
			(stroke
				(width 0.1)
				(type default)
			)
			(layer "B.Fab")
		)
		(fp_line
			(start -0.2794 0.9906)
			(end -0.2794 -0.1016)
			(stroke
				(width 0.1)
				(type default)
			)
			(layer "B.Fab")
		)
		(fp_line
			(start -0.2794 -0.1016)
			(end 0.2794 -0.1016)
			(stroke
				(width 0.1)
				(type default)
			)
			(layer "B.Fab")
		)
		(pad "1" smd rect
			(at 0 0)
			(size 0.508 0.508)
			(layers "B.Cu" "B.Mask" "B.Paste")
			(net "BMC_TCK_MUX_SEL")
		)
		(pad "2" smd rect
			(at 0 0.889)
			(size 0.508 0.508)
			(layers "B.Cu" "B.Mask" "B.Paste")
			(net "GND")
		)
		(zone
			(layer "B.Cu")
			(hatch none 0.5)
			(connect_pads
				(clearance 0)
			)
			(min_thickness 0.25)
			(keepout
				(tracks not_allowed)
				(vias allowed)
				(pads allowed)
				(copperpour not_allowed)
				(footprints allowed)
			)
			(placement
				(enabled no)
				(sheetname "")
			)
			(fill
				(thermal_gap 0.5)
				(thermal_bridge_width 0.5)
				(island_removal_mode 0)
			)
			(polygon
				(pts
					(xy 439.4073 -148.59) (xy 439.9153 -148.59) (xy 439.9153 -148.209) (xy 439.4073 -148.209)
				)
			)
		)
		(zone
			(layer "B.Cu")
			(hatch none 0.5)
			(connect_pads
				(clearance 0)
			)
			(min_thickness 0.25)
			(keepout
				(tracks allowed)
				(vias not_allowed)
				(pads allowed)
				(copperpour not_allowed)
				(footprints allowed)
			)
			(placement
				(enabled no)
				(sheetname "")
			)
			(fill
				(thermal_gap 0.5)
				(thermal_bridge_width 0.5)
				(island_removal_mode 0)
			)
			(polygon
				(pts
					(xy 439.4073 -148.209) (xy 439.9153 -148.209) (xy 439.9153 -148.59) (xy 439.4073 -148.59)
				)
			)
		)
	)
	(footprint ""
		(layer "B.Cu")
		(at 441.119006 -41.648126 180)
		(property "Reference" "R25W24"
			(at 0 0 0)
			(layer "B.SilkS")
			(hide yes)
			(effects
				(font
					(size 1.27 1.27)
				)
				(justify mirror)
			)
		)
		(property "Value" "*"
			(at -0.064008 -4.108196 180)
			(unlocked yes)
			(layer "B.Fab")
			(hide yes)
			(effects
				(font
					(size 1.27 1.016)
					(thickness 0.1524)
				)
				(justify mirror)
			)
		)
		(property "Device Type" "120R2F-GP_RCL_GP-120R2F-GP,64.A"
			(at -0.064008 -5.632196 180)
			(unlocked yes)
			(layer "B.Fab")
			(hide yes)
			(effects
				(font
					(size 1.27 1.016)
					(thickness 0.1524)
				)
				(justify mirror)
			)
		)
		(duplicate_pad_numbers_are_jumpers no)
		(fp_line
			(start 0.508 -0.9398)
			(end 0.508 0.9398)
			(stroke
				(width 0.1524)
				(type default)
			)
			(layer "B.SilkS")
		)
		(fp_line
			(start -0.508 -0.9398)
			(end 0.508 -0.9398)
			(stroke
				(width 0.1524)
				(type default)
			)
			(layer "B.SilkS")
		)
		(fp_rect
			(start 0.508 0.9398)
			(end -0.508 -0.9398)
			(stroke
				(width 0)
				(type default)
			)
			(fill no)
			(layer "B.CrtYd")
		)
		(fp_rect
			(start 0.508 0.9398)
			(end -0.508 -0.9398)
			(stroke
				(width 0)
				(type default)
			)
			(fill no)
			(layer "B.Fab")
		)
		(pad "1" smd custom
			(at 0 -0.4445)
			(size 0.1397 0.1397)
			(layers "B.Cu" "B.Mask" "B.Paste")
			(net "GND")
			(options
				(clearance outline)
				(anchor circle)
			)
			(primitives
				(gr_poly
					(pts
						(arc
							(start -0.1778 0.2794)
							(mid -0.249642 0.249642)
							(end -0.2794 0.1778)
						)
						(arc
							(start -0.2794 -0.1778)
							(mid -0.249642 -0.249642)
							(end -0.1778 -0.2794)
						)
						(arc
							(start 0.1778 -0.2794)
							(mid 0.249642 -0.249642)
							(end 0.2794 -0.1778)
						)
						(arc
							(start 0.2794 0.1778)
							(mid 0.249642 0.249642)
							(end 0.1778 0.2794)
						)
					)
					(width 0)
					(fill yes)
				)
			)
		)
		(pad "2" smd custom
			(at 0 0.4445)
			(size 0.1397 0.1397)
			(layers "B.Cu" "B.Mask" "B.Paste")
			(net "BMC_M_A12")
			(options
				(clearance outline)
				(anchor circle)
			)
			(primitives
				(gr_poly
					(pts
						(arc
							(start -0.1778 0.2794)
							(mid -0.249642 0.249642)
							(end -0.2794 0.1778)
						)
						(arc
							(start -0.2794 -0.1778)
							(mid -0.249642 -0.249642)
							(end -0.1778 -0.2794)
						)
						(arc
							(start 0.1778 -0.2794)
							(mid 0.249642 -0.249642)
							(end 0.2794 -0.1778)
						)
						(arc
							(start 0.2794 0.1778)
							(mid 0.249642 0.249642)
							(end 0.1778 0.2794)
						)
					)
					(width 0)
					(fill yes)
				)
			)
		)
	)
	(footprint ""
		(layer "B.Cu")
		(at 344.435176 -77.694536 180)
		(property "Reference" "C3P18"
			(at 0 0 0)
			(layer "B.SilkS")
			(hide yes)
			(effects
				(font
					(size 1.27 1.27)
				)
				(justify mirror)
			)
		)
		(property "Value" ""
			(at 0 0 0)
			(layer "B.Fab")
			(effects
				(font
					(size 1.27 1.27)
				)
				(justify mirror)
			)
		)
		(duplicate_pad_numbers_are_jumpers no)
		(fp_poly
			(pts
				(xy -0.3048 -0.1016) (xy -0.3048 0.9906) (xy 0.3048 0.9906) (xy 0.3048 -0.1016)
			)
			(stroke
				(width 0)
				(type default)
			)
			(fill no)
			(layer "B.CrtYd")
		)
		(fp_line
			(start 0.3048 0.9906)
			(end -0.3048 0.9906)
			(stroke
				(width 0.1)
				(type default)
			)
			(layer "B.Fab")
		)
		(fp_line
			(start 0.3048 -0.1016)
			(end 0.3048 0.9906)
			(stroke
				(width 0.1)
				(type default)
			)
			(layer "B.Fab")
		)
		(fp_line
			(start -0.3048 0.9906)
			(end -0.3048 -0.1016)
			(stroke
				(width 0.1)
				(type default)
			)
			(layer "B.Fab")
		)
		(fp_line
			(start -0.3048 -0.1016)
			(end 0.3048 -0.1016)
			(stroke
				(width 0.1)
				(type default)
			)
			(layer "B.Fab")
		)
		(pad "1" smd rect
			(at 0 0)
			(size 0.508 0.508)
			(layers "B.Cu" "B.Mask" "B.Paste")
			(net "P3E_CPU0_PE1_SS_TXP<2>")
		)
		(pad "2" smd rect
			(at 0 0.889)
			(size 0.508 0.508)
			(layers "B.Cu" "B.Mask" "B.Paste")
			(net "P3E_CPU0_PE1_PCH_TXP<2>")
		)
		(zone
			(layer "B.Cu")
			(hatch none 0.5)
			(connect_pads
				(clearance 0)
			)
			(min_thickness 0.25)
			(keepout
				(tracks allowed)
				(vias not_allowed)
				(pads allowed)
				(copperpour not_allowed)
				(footprints allowed)
			)
			(placement
				(enabled no)
				(sheetname "")
			)
			(fill
				(thermal_gap 0.5)
				(thermal_bridge_width 0.5)
				(island_removal_mode 0)
			)
			(polygon
				(pts
					(xy 344.181176 -77.948536) (xy 344.689176 -77.948536) (xy 344.689176 -78.329536) (xy 344.181176 -78.329536)
				)
			)
		)
	)
)
